FILE_TYPE = CONNECTIVITY;
{Allegro Design Entry HDL 17.4-2019 S026 (4007227) 1/17/2022}
"PAGE_NUMBER" = 417;
0"NC";
1"P5E_CPU0_P2_RX_BUF_DN<15:8>";
2"P5E_CPU0_P2_RX_BUF_DP<15:8>";
3"P5E_CPU0_P2_RX_BUF_DN<7:0>";
4"P5E_CPU0_P2_RX_BUF_DP<7:0>";
5"P5E_CPU0_P2_RX_BUF_DN<15>";
6"P5E_CPU0_P2_RX_BUF_DP<15>";
7"P5E_CPU0_P2_RX_BUF_DP<14>";
8"P5E_CPU0_P2_RX_BUF_DN<14>";
9"P5E_CPU0_P2_RX_BUF_DP<13>";
10"P5E_CPU0_P2_RX_BUF_DN<12>";
11"P5E_CPU0_P2_RX_BUF_DP<11>";
12"P5E_CPU0_P2_RX_BUF_DN<11>";
13"P5E_CPU0_P2_RX_BUF_DP<10>";
14"P5E_CPU0_P2_RX_BUF_DP<5>";
15"P5E_CPU0_P2_RX_BUF_DN<5>";
16"P5E_CPU0_P2_RX_BUF_DN<4>";
17"P5E_CPU0_P2_RX_BUF_DN<7>";
18"P5E_CPU0_P2_RX_BUF_DN<1>";
19"P5E_CPU0_P2_RX_BUF_DP<0>";
20"P5E_CPU0_P2_RX_BUF_DN<6>";
21"P5E_CPU0_P2_RX_BUF_DN<13>";
22"P5E_CPU0_P2_RX_BUF_DP<12>";
23"P5E_CPU0_P2_RX_BUF_DN<9>";
24"P5E_CPU0_P2_RX_BUF_DP<8>";
25"P5E_CPU0_P2_RX_BUF_DP<6>";
26"P5E_CPU0_P2_RX_BUF_DN<8>";
27"P5E_CPU0_P2_RX_BUF_DP<3>";
28"P5E_CPU0_P2_RX_BUF_DN<3>";
29"P5E_CPU0_P2_RX_BUF_DP<7>";
30"P5E_CPU0_P2_RX_BUF_DP<4>";
31"P5E_CPU0_P2_RX_BUF_DN<2>";
32"P5E_CPU0_P2_RX_BUF_DP<2>";
33"P5E_CPU0_P2_RX_BUF_DP<1>";
34"P5E_CPU0_P2_RX_BUF_DN<0>";
35"P5E_CPU0_P2_RX_BUF_DP<9>";
36"P5E_CPU0_P2_RX_BUF_DN<10>";
%"PT5161LRS"
"1","(-7525,3800)","0","pure_quanta","I1";
;
LOCATION"U6012"
$SEC"1"
CDS_SEC"1"
MATERIAL"IC"
PART_TYPE"SMLF"
VALUE"PT5161LRS"
CDS_LIB"pure_quanta"
CDS_LMAN_SYM_OUTLINE"-350,1450,300,-1400"
NEEDS_NO_SIZE"TRUE"
PART_NUMBER"AJ051610U03";
"A_PERN7"
$PN"CB2"26;
"A_PERP7"
$PN"CD1"24;
"A_PERN6"
$PN"BR2"23;
"A_PERP6"
$PN"BU1"35;
"A_PERN5"
$PN"BH2"36;
"A_PERP5"
$PN"BK1"13;
"A_PERN4"
$PN"BA2"12;
"A_PERP4"
$PN"BC1"11;
"A_PERN3"
$PN"AP2"10;
"A_PERP3"
$PN"AT1"22;
"A_PERN2"
$PN"AG2"21;
"A_PERP2"
$PN"AJ1"9;
"A_PERN1"
$PN"Y2"8;
"A_PERP1"
$PN"AB1"7;
"A_PERN0"
$PN"N2"5;
"A_PERP0"
$PN"R1"6;
%"TAP"
"1","(-6500,4000)","0","standard","I10";
;
CDS_LIB"standard"
BODY_TYPE"PLUMBING"
HDL_TAP"TRUE";
"B \NAC \NWC"2;
"S \NAC"
BN"12"22;
%"TAP"
"1","(-6300,3900)","0","standard","I11";
;
CDS_LIB"standard"
BODY_TYPE"PLUMBING"
HDL_TAP"TRUE";
"B \NAC \NWC"1;
"S \NAC"
BN"12"10;
%"TAP"
"1","(-6300,4250)","0","standard","I12";
;
CDS_LIB"standard"
BODY_TYPE"PLUMBING"
HDL_TAP"TRUE";
"B \NAC \NWC"1;
"S \NAC"
BN"13"21;
%"TAP"
"1","(-6500,4350)","0","standard","I13";
;
CDS_LIB"standard"
BODY_TYPE"PLUMBING"
HDL_TAP"TRUE";
"B \NAC \NWC"2;
"S \NAC"
BN"13"9;
%"TAP"
"1","(-6500,4700)","0","standard","I14";
;
CDS_LIB"standard"
BODY_TYPE"PLUMBING"
HDL_TAP"TRUE";
"B \NAC \NWC"2;
"S \NAC"
BN"14"7;
%"TAP"
"1","(-6300,4600)","0","standard","I15";
;
CDS_LIB"standard"
BODY_TYPE"PLUMBING"
HDL_TAP"TRUE";
"B \NAC \NWC"1;
"S \NAC"
BN"14"8;
%"TAP"
"1","(-6300,4950)","0","standard","I16";
;
CDS_LIB"standard"
BODY_TYPE"PLUMBING"
HDL_TAP"TRUE";
"B \NAC \NWC"1;
"S \NAC"
BN"15"5;
%"TAP"
"1","(-6500,5050)","0","standard","I17";
;
CDS_LIB"standard"
BODY_TYPE"PLUMBING"
HDL_TAP"TRUE";
"B \NAC \NWC"2;
"S \NAC"
BN"15"6;
%"TAP"
"1","(-6500,2600)","0","standard","I2";
;
CDS_LIB"standard"
BODY_TYPE"PLUMBING"
HDL_TAP"TRUE";
"B \NAC \NWC"2;
"S \NAC"
BN"8"24;
%"TAP"
"1","(-2050,2625)","0","standard","I20";
;
CDS_LIB"standard"
BODY_TYPE"PLUMBING"
HDL_TAP"TRUE";
"B \NAC \NWC"4;
"S \NAC"
BN"0"19;
%"TAP"
"1","(-1850,2525)","0","standard","I21";
;
CDS_LIB"standard"
BODY_TYPE"PLUMBING"
HDL_TAP"TRUE";
"B \NAC \NWC"3;
"S \NAC"
BN"0"34;
%"TAP"
"1","(-2050,2975)","0","standard","I22";
;
CDS_LIB"standard"
BODY_TYPE"PLUMBING"
HDL_TAP"TRUE";
"B \NAC \NWC"4;
"S \NAC"
BN"1"33;
%"TAP"
"1","(-1850,2875)","0","standard","I23";
;
CDS_LIB"standard"
BODY_TYPE"PLUMBING"
HDL_TAP"TRUE";
"B \NAC \NWC"3;
"S \NAC"
BN"1"18;
%"TAP"
"1","(-1850,3225)","0","standard","I24";
;
CDS_LIB"standard"
BODY_TYPE"PLUMBING"
HDL_TAP"TRUE";
"B \NAC \NWC"3;
"S \NAC"
BN"2"31;
%"TAP"
"1","(-2050,3325)","0","standard","I25";
;
CDS_LIB"standard"
BODY_TYPE"PLUMBING"
HDL_TAP"TRUE";
"B \NAC \NWC"4;
"S \NAC"
BN"2"32;
%"TAP"
"1","(-2050,3675)","0","standard","I26";
;
CDS_LIB"standard"
BODY_TYPE"PLUMBING"
HDL_TAP"TRUE";
"B \NAC \NWC"4;
"S \NAC"
BN"3"27;
%"TAP"
"1","(-1850,3575)","0","standard","I27";
;
CDS_LIB"standard"
BODY_TYPE"PLUMBING"
HDL_TAP"TRUE";
"B \NAC \NWC"3;
"S \NAC"
BN"3"28;
%"TAP"
"1","(-2050,4025)","0","standard","I28";
;
CDS_LIB"standard"
BODY_TYPE"PLUMBING"
HDL_TAP"TRUE";
"B \NAC \NWC"4;
"S \NAC"
BN"4"30;
%"TAP"
"1","(-1850,3925)","0","standard","I29";
;
CDS_LIB"standard"
BODY_TYPE"PLUMBING"
HDL_TAP"TRUE";
"B \NAC \NWC"3;
"S \NAC"
BN"4"16;
%"TAP"
"1","(-6300,2500)","0","standard","I3";
;
CDS_LIB"standard"
BODY_TYPE"PLUMBING"
HDL_TAP"TRUE";
"B \NAC \NWC"1;
"S \NAC"
BN"8"26;
%"TAP"
"1","(-2050,4375)","0","standard","I30";
;
CDS_LIB"standard"
BODY_TYPE"PLUMBING"
HDL_TAP"TRUE";
"B \NAC \NWC"4;
"S \NAC"
BN"5"14;
%"TAP"
"1","(-2050,4725)","0","standard","I31";
;
CDS_LIB"standard"
BODY_TYPE"PLUMBING"
HDL_TAP"TRUE";
"B \NAC \NWC"4;
"S \NAC"
BN"6"25;
%"TAP"
"1","(-1850,4275)","0","standard","I32";
;
CDS_LIB"standard"
BODY_TYPE"PLUMBING"
HDL_TAP"TRUE";
"B \NAC \NWC"3;
"S \NAC"
BN"5"15;
%"TAP"
"1","(-1850,4625)","0","standard","I33";
;
CDS_LIB"standard"
BODY_TYPE"PLUMBING"
HDL_TAP"TRUE";
"B \NAC \NWC"3;
"S \NAC"
BN"6"20;
%"TAP"
"1","(-2050,5075)","0","standard","I34";
;
CDS_LIB"standard"
BODY_TYPE"PLUMBING"
HDL_TAP"TRUE";
"B \NAC \NWC"4;
"S \NAC"
BN"7"29;
%"TAP"
"1","(-1850,4975)","0","standard","I35";
;
CDS_LIB"standard"
BODY_TYPE"PLUMBING"
HDL_TAP"TRUE";
"B \NAC \NWC"3;
"S \NAC"
BN"7"17;
%"PT5161LRS"
"2","(-3075,3825)","0","pure_quanta","I38";
;
LOCATION"U6012"
$SEC"2"
CDS_SEC"2"
VALUE"PT5161LRS"
MATERIAL"IC"
PART_TYPE"SMLF"
NEEDS_NO_SIZE"TRUE"
CDS_LMAN_SYM_OUTLINE"-350,1450,300,-1400"
CDS_LIB"pure_quanta"
PART_NUMBER"AJ051610U03";
"A_PERN15"
$PN"EV2"34;
"A_PERP15"
$PN"EY1"19;
"A_PERN14"
$PN"EL2"18;
"A_PERP14"
$PN"EN1"33;
"A_PERN13"
$PN"ED2"31;
"A_PERP13"
$PN"EF1"32;
"A_PERN12"
$PN"DU2"28;
"A_PERP12"
$PN"DW1"27;
"A_PERN11"
$PN"DK2"16;
"A_PERP11"
$PN"DM1"30;
"A_PERN10"
$PN"DC2"15;
"A_PERP10"
$PN"DE1"14;
"A_PERN9"
$PN"CT2"20;
"A_PERP9"
$PN"CV1"25;
"A_PERN8"
$PN"CJ2"17;
"A_PERP8"
$PN"CL1"29;
%"TAP"
"1","(-6500,2950)","0","standard","I4";
;
CDS_LIB"standard"
BODY_TYPE"PLUMBING"
HDL_TAP"TRUE";
"B \NAC \NWC"2;
"S \NAC"
BN"9"35;
%"TAP"
"1","(-6300,2850)","0","standard","I5";
;
CDS_LIB"standard"
BODY_TYPE"PLUMBING"
HDL_TAP"TRUE";
"B \NAC \NWC"1;
"S \NAC"
BN"9"23;
%"TAP"
"1","(-6300,3200)","0","standard","I6";
;
CDS_LIB"standard"
BODY_TYPE"PLUMBING"
HDL_TAP"TRUE";
"B \NAC \NWC"1;
"S \NAC"
BN"10"36;
%"TAP"
"1","(-6500,3300)","0","standard","I7";
;
CDS_LIB"standard"
BODY_TYPE"PLUMBING"
HDL_TAP"TRUE";
"B \NAC \NWC"2;
"S \NAC"
BN"10"13;
%"TAP"
"1","(-6300,3550)","0","standard","I8";
;
CDS_LIB"standard"
BODY_TYPE"PLUMBING"
HDL_TAP"TRUE";
"B \NAC \NWC"1;
"S \NAC"
BN"11"12;
%"TAP"
"1","(-6500,3650)","0","standard","I9";
;
CDS_LIB"standard"
BODY_TYPE"PLUMBING"
HDL_TAP"TRUE";
"B \NAC \NWC"2;
"S \NAC"
BN"11"11;
END.
